# S9S_MB_2U (Grand Teton) — schematic netlist excerpt (pin names and nets, part order shuffled) for the footprints in the layout excerpt that follows; sources: Cadence DE-HDL packaged netlist, KiCad conversion of 03242023_DA0F0TMBIJ0_F0T_Motherboard_J_brd_V01_OCP.brd

R2725  Q_RES  0 5% CHIP  pkg 0402LF  page 234 : A = I3C_BMC_SWB_R_SCL ; B = I3C_BMC_SWB_BUF_R_SCL
D66  Q_LED  IC  pkg SMLF  page 256 : A = LED_RST_PLD_CPU0_DRAM_CD_N ; C = LED_RST_PLD_CPU0_DRAM_CD_N_D

(kicad_pcb
	(version 20260206)
	(generator "pcbnew")
	(generator_version "10.0")
	(general
		(thickness 1.6)
		(legacy_teardrops no)
	)
	(paper "A4")
	(title_block
		(title "03242023_DA0F0TMBIJ0_F0T_Motherboard_J_brd_V01_OCP.brd")
		(comment 1 "Grand Teton / footprints 2981-2982 of 6105")
	)
	(layers
		(0 "F.Cu" signal "TOP")
		(4 "In1.Cu" signal "GND")
		(6 "In2.Cu" signal "IN1")
		(8 "In3.Cu" signal "GND1")
		(10 "In4.Cu" signal "IN2")
		(12 "In5.Cu" signal "GND2")
		(14 "In6.Cu" signal "IN3")
		(16 "In7.Cu" signal "GND3")
		(18 "In8.Cu" signal "VCC")
		(20 "In9.Cu" signal "VCC1")
		(22 "In10.Cu" signal "GND4")
		(24 "In11.Cu" signal "IN4")
		(26 "In12.Cu" signal "GND5")
		(28 "In13.Cu" signal "IN5")
		(30 "In14.Cu" signal "GND6")
		(32 "In15.Cu" signal "IN6")
		(34 "In16.Cu" signal "GND7")
		(2 "B.Cu" signal "BOTTOM")
		(9 "F.Adhes" user "F.Adhesive")
		(11 "B.Adhes" user "B.Adhesive")
		(13 "F.Paste" user "Package Geometry/Pastemask Top")
		(15 "B.Paste" user "Package Geometry/Pastemask Bottom")
		(5 "F.SilkS" user "Ref Des/Silkscreen Top")
		(7 "B.SilkS" user "Ref Des/Silkscreen Bottom")
		(1 "F.Mask" user "Board Geometry/Soldermask Top")
		(3 "B.Mask" user "Board Geometry/Soldermask Bottom")
		(17 "Dwgs.User" user "User.Drawings")
		(19 "Cmts.User" user "User.Comments")
		(21 "Eco1.User" user "User.Eco1")
		(23 "Eco2.User" user "User.Eco2")
		(25 "Edge.Cuts" user "Board Geometry/Outline")
		(27 "Margin" user)
		(31 "F.CrtYd" user "Package Geometry/Place Bound Top")
		(29 "B.CrtYd" user "Package Geometry/Place Bound Bottom")
		(35 "F.Fab" user "Ref Des/Assembly Top")
		(33 "B.Fab" user "Ref Des/Assembly Bottom")
	)
	(footprint ""
		(layer "F.Cu")
		(at 77.780896 -70.78599)
		(property "Reference" "D66"
			(at -40.319706 50.178462 90)
			(unlocked yes)
			(layer "F.SilkS")
			(effects
				(font
					(size 0.635 0.4064)
					(thickness 0.1524)
				)
				(justify left)
			)
		)
		(property "Value" ""
			(at 0 0 0)
			(layer "F.Fab")
			(effects
				(font
					(size 1.27 1.27)
				)
			)
		)
		(duplicate_pad_numbers_are_jumpers no)
		(fp_line
			(start -0.90678 0.4826)
			(end -0.90678 -0.4699)
			(stroke
				(width 0.1524)
				(type default)
			)
			(layer "F.SilkS")
		)
		(fp_line
			(start -0.89408 -0.4826)
			(end 0.90678 -0.4826)
			(stroke
				(width 0.1524)
				(type default)
			)
			(layer "F.SilkS")
		)
		(fp_line
			(start -0.79248 -0.4826)
			(end 1.03378 -0.4826)
			(stroke
				(width 0.1524)
				(type default)
			)
			(layer "F.SilkS")
		)
		(fp_line
			(start -0.64008 -0.4826)
			(end 1.16078 -0.4826)
			(stroke
				(width 0.1524)
				(type default)
			)
			(layer "F.SilkS")
		)
		(fp_line
			(start 0.90678 -0.4826)
			(end 0.90678 0.4826)
			(stroke
				(width 0.1524)
				(type default)
			)
			(layer "F.SilkS")
		)
		(fp_line
			(start 0.90678 0.4826)
			(end -0.90678 0.4826)
			(stroke
				(width 0.1524)
				(type default)
			)
			(layer "F.SilkS")
		)
		(fp_line
			(start 1.03378 -0.4826)
			(end 1.03378 0.4826)
			(stroke
				(width 0.1524)
				(type default)
			)
			(layer "F.SilkS")
		)
		(fp_line
			(start 1.03378 0.4826)
			(end -0.79248 0.4826)
			(stroke
				(width 0.1524)
				(type default)
			)
			(layer "F.SilkS")
		)
		(fp_line
			(start 1.16078 -0.4826)
			(end 1.16078 0.4826)
			(stroke
				(width 0.1524)
				(type default)
			)
			(layer "F.SilkS")
		)
		(fp_line
			(start 1.16078 0.4826)
			(end -0.64008 0.4826)
			(stroke
				(width 0.1524)
				(type default)
			)
			(layer "F.SilkS")
		)
		(fp_line
			(start -0.499872 -0.249936)
			(end 0.499872 -0.249936)
			(stroke
				(width 0.1)
				(type default)
			)
			(layer "F.Fab")
		)
		(fp_line
			(start -0.499872 0.249936)
			(end -0.499872 -0.249936)
			(stroke
				(width 0.1)
				(type default)
			)
			(layer "F.Fab")
		)
		(fp_line
			(start 0.499872 -0.249936)
			(end 0.499872 0.249936)
			(stroke
				(width 0.1)
				(type default)
			)
			(layer "F.Fab")
		)
		(fp_line
			(start 0.499872 0.249936)
			(end -0.499872 0.249936)
			(stroke
				(width 0.1)
				(type default)
			)
			(layer "F.Fab")
		)
		(pad "A" smd rect
			(at -0.47498 0)
			(size 0.6096 0.7112)
			(layers "F.Cu" "F.Mask" "F.Paste")
			(net "LED_RST_PLD_CPU0_DRAM_CD_N")
		)
		(pad "C" smd rect
			(at 0.47498 0)
			(size 0.6096 0.7112)
			(layers "F.Cu" "F.Mask" "F.Paste")
			(net "LED_RST_PLD_CPU0_DRAM_CD_N_D")
		)
	)
	(footprint ""
		(layer "F.Cu")
		(at 369.292632 -397.519398)
		(property "Reference" "R2725"
			(at 0 0 0)
			(layer "F.SilkS")
			(hide yes)
			(effects
				(font
					(size 1.27 1.27)
				)
			)
		)
		(property "Value" ""
			(at 0 0 0)
			(layer "F.Fab")
			(effects
				(font
					(size 1.27 1.27)
				)
			)
		)
		(duplicate_pad_numbers_are_jumpers no)
		(fp_line
			(start -0.7874 -0.4064)
			(end 0.7874 -0.4064)
			(stroke
				(width 0.1524)
				(type default)
			)
			(layer "F.SilkS")
		)
		(fp_line
			(start -0.7874 0.4064)
			(end -0.7874 -0.4064)
			(stroke
				(width 0.1524)
				(type default)
			)
			(layer "F.SilkS")
		)
		(fp_line
			(start 0.7874 -0.4064)
			(end 0.7874 0.4064)
			(stroke
				(width 0.1524)
				(type default)
			)
			(layer "F.SilkS")
		)
		(fp_line
			(start 0.7874 0.4064)
			(end -0.7874 0.4064)
			(stroke
				(width 0.1524)
				(type default)
			)
			(layer "F.SilkS")
		)
		(fp_line
			(start -0.67945 -0.305054)
			(end -0.12065 -0.305054)
			(stroke
				(width 0.1)
				(type default)
			)
			(layer "F.Fab")
		)
		(fp_line
			(start -0.67945 0.3048)
			(end -0.67945 -0.305054)
			(stroke
				(width 0.1)
				(type default)
			)
			(layer "F.Fab")
		)
		(fp_line
			(start -0.12065 -0.305054)
			(end -0.12065 -0.2794)
			(stroke
				(width 0.1)
				(type default)
			)
			(layer "F.Fab")
		)
		(fp_line
			(start -0.12065 -0.2794)
			(end 0.12065 -0.2794)
			(stroke
				(width 0.1)
				(type default)
			)
			(layer "F.Fab")
		)
		(fp_line
			(start -0.12065 0.2794)
			(end -0.12065 0.3048)
			(stroke
				(width 0.1)
				(type default)
			)
			(layer "F.Fab")
		)
		(fp_line
			(start -0.12065 0.3048)
			(end -0.67945 0.3048)
			(stroke
				(width 0.1)
				(type default)
			)
			(layer "F.Fab")
		)
		(fp_line
			(start 0.120396 0.2794)
			(end -0.12065 0.2794)
			(stroke
				(width 0.1)
				(type default)
			)
			(layer "F.Fab")
		)
		(fp_line
			(start 0.120396 0.3048)
			(end 0.120396 0.2794)
			(stroke
				(width 0.1)
				(type default)
			)
			(layer "F.Fab")
		)
		(fp_line
			(start 0.12065 -0.3048)
			(end 0.67945 -0.3048)
			(stroke
				(width 0.1)
				(type default)
			)
			(layer "F.Fab")
		)
		(fp_line
			(start 0.12065 -0.2794)
			(end 0.12065 -0.3048)
			(stroke
				(width 0.1)
				(type default)
			)
			(layer "F.Fab")
		)
		(fp_line
			(start 0.67945 -0.3048)
			(end 0.67945 0.3048)
			(stroke
				(width 0.1)
				(type default)
			)
			(layer "F.Fab")
		)
		(fp_line
			(start 0.67945 0.3048)
			(end 0.120396 0.3048)
			(stroke
				(width 0.1)
				(type default)
			)
			(layer "F.Fab")
		)
		(pad "1" smd circle
			(at -0.40005 0)
			(size 0 0)
			(layers "F.Cu" "F.Mask" "F.Paste")
			(net "I3C_BMC_SWB_R_SCL")
		)
		(pad "2" smd circle
			(at 0.40005 0)
			(size 0 0)
			(layers "F.Cu" "F.Mask" "F.Paste")
			(net "I3C_BMC_SWB_BUF_R_SCL")
		)
	)
)
